# S9S_MB_2U (Grand Teton) — schematic netlist excerpt (pin names and nets, part order shuffled) for the footprints in the layout excerpt that follows; sources: Cadence DE-HDL packaged netlist, KiCad conversion of 03242023_DA0F0TMBIJ0_F0T_Motherboard_J_brd_V01_OCP.brd

R3890  Q_RES  49.9 1% CHIP  pkg 0402LF  page 97 : A = I3C_SPD_DDREFGH_CPU0_LVC1_SCL_7 ; B = I3C_SPD_DDREFGH_CPU0_LVC1_SCL

U223  74CBTLV3126PW  IC  pkg TSSOP14  page 160
  \1oe\  = FB_BMC_ISOLATE1
  \1a\  = NCSI_BMC_TXD1_R1
  \1b\  = NCSI_OCP_V3_2_TXD1
  \2oe\  = FB_BMC_ISOLATE1
  \2a\  = NCSI_BMC_TXD0_R1
  \2b\  = NCSI_OCP_V3_2_TXD0
  GND  = GND
  \3b\  = NCSI_OCP_V3_2_TX_EN
  \3a\  = NCSI_BMC_TX_EN_R1
  \3oe\  = FB_BMC_ISOLATE1
  \4b\  = OCP_V3_2_ISO2_RBT_ARB_OUT
  \4a\  = OCP_V3_2_RBT_ARB_OUT
  \4oe\  = FB_BMC_ISOLATE1
  VCC  = P3V3_AUX

(kicad_pcb
	(version 20260206)
	(generator "pcbnew")
	(generator_version "10.0")
	(general
		(thickness 1.6)
		(legacy_teardrops no)
	)
	(paper "A4")
	(title_block
		(title "03242023_DA0F0TMBIJ0_F0T_Motherboard_J_brd_V01_OCP.brd")
		(comment 1 "Grand Teton / footprints 4159-4160 of 6105")
	)
	(layers
		(0 "F.Cu" signal "TOP")
		(4 "In1.Cu" signal "GND")
		(6 "In2.Cu" signal "IN1")
		(8 "In3.Cu" signal "GND1")
		(10 "In4.Cu" signal "IN2")
		(12 "In5.Cu" signal "GND2")
		(14 "In6.Cu" signal "IN3")
		(16 "In7.Cu" signal "GND3")
		(18 "In8.Cu" signal "VCC")
		(20 "In9.Cu" signal "VCC1")
		(22 "In10.Cu" signal "GND4")
		(24 "In11.Cu" signal "IN4")
		(26 "In12.Cu" signal "GND5")
		(28 "In13.Cu" signal "IN5")
		(30 "In14.Cu" signal "GND6")
		(32 "In15.Cu" signal "IN6")
		(34 "In16.Cu" signal "GND7")
		(2 "B.Cu" signal "BOTTOM")
		(9 "F.Adhes" user "F.Adhesive")
		(11 "B.Adhes" user "B.Adhesive")
		(13 "F.Paste" user "Package Geometry/Pastemask Top")
		(15 "B.Paste" user "Package Geometry/Pastemask Bottom")
		(5 "F.SilkS" user "Ref Des/Silkscreen Top")
		(7 "B.SilkS" user "Ref Des/Silkscreen Bottom")
		(1 "F.Mask" user "Board Geometry/Soldermask Top")
		(3 "B.Mask" user "Board Geometry/Soldermask Bottom")
		(17 "Dwgs.User" user "User.Drawings")
		(19 "Cmts.User" user "User.Comments")
		(21 "Eco1.User" user "User.Eco1")
		(23 "Eco2.User" user "User.Eco2")
		(25 "Edge.Cuts" user "Board Geometry/Outline")
		(27 "Margin" user)
		(31 "F.CrtYd" user "Package Geometry/Place Bound Top")
		(29 "B.CrtYd" user "Package Geometry/Place Bound Bottom")
		(35 "F.Fab" user "Ref Des/Assembly Top")
		(33 "B.Fab" user "Ref Des/Assembly Bottom")
	)
	(footprint ""
		(layer "B.Cu")
		(at 198.47433 -70.903084)
		(property "Reference" "U223"
			(at 3.66141 -3.162554 0)
			(unlocked yes)
			(layer "B.SilkS")
			(effects
				(font
					(size 0.7874 0.5842)
					(thickness 0.1524)
				)
				(justify left mirror)
			)
		)
		(property "Value" ""
			(at 0 0 0)
			(layer "B.Fab")
			(effects
				(font
					(size 1.27 1.27)
				)
				(justify mirror)
			)
		)
		(duplicate_pad_numbers_are_jumpers no)
		(fp_line
			(start -2.0066 -2.5527)
			(end -2.0066 2.5527)
			(stroke
				(width 0.1524)
				(type default)
			)
			(layer "B.SilkS")
		)
		(fp_line
			(start -2.0066 2.5527)
			(end 2.0066 2.5527)
			(stroke
				(width 0.1524)
				(type default)
			)
			(layer "B.SilkS")
		)
		(fp_line
			(start -0.5715 -2.5527)
			(end -2.0066 -2.5527)
			(stroke
				(width 0.1524)
				(type default)
			)
			(layer "B.SilkS")
		)
		(fp_line
			(start 0 -1.9812)
			(end -0.5715 -2.5527)
			(stroke
				(width 0.1524)
				(type default)
			)
			(layer "B.SilkS")
		)
		(fp_line
			(start 0.5715 -2.5527)
			(end 0 -1.9812)
			(stroke
				(width 0.1524)
				(type default)
			)
			(layer "B.SilkS")
		)
		(fp_line
			(start 2.0066 -2.5527)
			(end 0.5715 -2.5527)
			(stroke
				(width 0.1524)
				(type default)
			)
			(layer "B.SilkS")
		)
		(fp_line
			(start 2.0066 2.5527)
			(end 2.0066 -2.5527)
			(stroke
				(width 0.1524)
				(type default)
			)
			(layer "B.SilkS")
		)
		(fp_poly
			(pts
				(xy 4.36372 -1.608328) (xy 3.81 -1.905) (xy 4.36372 -2.233168)
			)
			(stroke
				(width 0)
				(type default)
			)
			(fill yes)
			(layer "B.SilkS")
		)
		(fp_line
			(start -2.249932 -2.549906)
			(end -2.249932 2.549906)
			(stroke
				(width 0.1)
				(type default)
			)
			(layer "B.Fab")
		)
		(fp_line
			(start -2.249932 2.549906)
			(end 2.249932 2.549906)
			(stroke
				(width 0.1)
				(type default)
			)
			(layer "B.Fab")
		)
		(fp_line
			(start 2.249932 -2.549906)
			(end -2.249932 -2.549906)
			(stroke
				(width 0.1)
				(type default)
			)
			(layer "B.Fab")
		)
		(fp_line
			(start 2.249932 2.549906)
			(end 2.249932 -2.549906)
			(stroke
				(width 0.1)
				(type default)
			)
			(layer "B.Fab")
		)
		(fp_poly
			(pts
				(xy 4.36372 -1.608328) (xy 4.36372 -2.233168) (xy 3.81 -1.905)
			)
			(stroke
				(width 0)
				(type default)
			)
			(fill yes)
			(layer "B.Fab")
		)
		(pad "1" smd rect
			(at 2.921 -1.949958 270)
			(size 0.3556 1.4986)
			(layers "B.Cu" "B.Mask" "B.Paste")
			(net "FB_BMC_ISOLATE1")
		)
		(pad "2" smd rect
			(at 2.921 -1.299972 270)
			(size 0.3556 1.4986)
			(layers "B.Cu" "B.Mask" "B.Paste")
			(net "NCSI_BMC_TXD1_R1")
		)
		(pad "3" smd rect
			(at 2.921 -0.649986 270)
			(size 0.3556 1.4986)
			(layers "B.Cu" "B.Mask" "B.Paste")
			(net "NCSI_OCP_V3_2_TXD1")
		)
		(pad "4" smd rect
			(at 2.921 0 270)
			(size 0.3556 1.4986)
			(layers "B.Cu" "B.Mask" "B.Paste")
			(net "FB_BMC_ISOLATE1")
		)
		(pad "5" smd rect
			(at 2.921 0.649986 270)
			(size 0.3556 1.4986)
			(layers "B.Cu" "B.Mask" "B.Paste")
			(net "NCSI_BMC_TXD0_R1")
		)
		(pad "6" smd rect
			(at 2.921 1.299972 270)
			(size 0.3556 1.4986)
			(layers "B.Cu" "B.Mask" "B.Paste")
			(net "NCSI_OCP_V3_2_TXD0")
		)
		(pad "7" smd rect
			(at 2.921 1.949958 270)
			(size 0.3556 1.4986)
			(layers "B.Cu" "B.Mask" "B.Paste")
			(net "GND")
		)
		(pad "8" smd rect
			(at -2.921 1.949958 270)
			(size 0.3556 1.4986)
			(layers "B.Cu" "B.Mask" "B.Paste")
			(net "NCSI_OCP_V3_2_TX_EN")
		)
		(pad "9" smd rect
			(at -2.921 1.299972 270)
			(size 0.3556 1.4986)
			(layers "B.Cu" "B.Mask" "B.Paste")
			(net "NCSI_BMC_TX_EN_R1")
		)
		(pad "10" smd rect
			(at -2.921 0.649986 270)
			(size 0.3556 1.4986)
			(layers "B.Cu" "B.Mask" "B.Paste")
			(net "FB_BMC_ISOLATE1")
		)
		(pad "11" smd rect
			(at -2.921 0 270)
			(size 0.3556 1.4986)
			(layers "B.Cu" "B.Mask" "B.Paste")
			(net "OCP_V3_2_ISO2_RBT_ARB_OUT")
		)
		(pad "12" smd rect
			(at -2.921 -0.649986 270)
			(size 0.3556 1.4986)
			(layers "B.Cu" "B.Mask" "B.Paste")
			(net "OCP_V3_2_RBT_ARB_OUT")
		)
		(pad "13" smd rect
			(at -2.921 -1.299972 270)
			(size 0.3556 1.4986)
			(layers "B.Cu" "B.Mask" "B.Paste")
			(net "FB_BMC_ISOLATE1")
		)
		(pad "14" smd rect
			(at -2.921 -1.949958 270)
			(size 0.3556 1.4986)
			(layers "B.Cu" "B.Mask" "B.Paste")
			(net "P3V3_AUX")
		)
	)
	(footprint ""
		(layer "B.Cu")
		(at 451.812406 -317.15583 90)
		(property "Reference" "R3890"
			(at 0 0 90)
			(layer "B.SilkS")
			(hide yes)
			(effects
				(font
					(size 1.27 1.27)
				)
				(justify mirror)
			)
		)
		(property "Value" ""
			(at 0 0 90)
			(layer "B.Fab")
			(effects
				(font
					(size 1.27 1.27)
				)
				(justify mirror)
			)
		)
		(duplicate_pad_numbers_are_jumpers no)
		(fp_line
			(start 0.7874 -0.4064)
			(end -0.7874 -0.4064)
			(stroke
				(width 0.1524)
				(type default)
			)
			(layer "B.SilkS")
		)
		(fp_line
			(start -0.7874 -0.4064)
			(end -0.7874 0.4064)
			(stroke
				(width 0.1524)
				(type default)
			)
			(layer "B.SilkS")
		)
		(fp_line
			(start 0.7874 0.4064)
			(end 0.7874 -0.4064)
			(stroke
				(width 0.1524)
				(type default)
			)
			(layer "B.SilkS")
		)
		(fp_line
			(start -0.7874 0.4064)
			(end 0.7874 0.4064)
			(stroke
				(width 0.1524)
				(type default)
			)
			(layer "B.SilkS")
		)
		(fp_line
			(start 0.67945 -0.305054)
			(end 0.12065 -0.305054)
			(stroke
				(width 0.1)
				(type default)
			)
			(layer "B.Fab")
		)
		(fp_line
			(start 0.12065 -0.305054)
			(end 0.12065 -0.2794)
			(stroke
				(width 0.1)
				(type default)
			)
			(layer "B.Fab")
		)
		(fp_line
			(start -0.12065 -0.3048)
			(end -0.67945 -0.3048)
			(stroke
				(width 0.1)
				(type default)
			)
			(layer "B.Fab")
		)
		(fp_line
			(start -0.67945 -0.3048)
			(end -0.67945 0.3048)
			(stroke
				(width 0.1)
				(type default)
			)
			(layer "B.Fab")
		)
		(fp_line
			(start 0.12065 -0.2794)
			(end -0.12065 -0.2794)
			(stroke
				(width 0.1)
				(type default)
			)
			(layer "B.Fab")
		)
		(fp_line
			(start -0.12065 -0.2794)
			(end -0.12065 -0.3048)
			(stroke
				(width 0.1)
				(type default)
			)
			(layer "B.Fab")
		)
		(fp_line
			(start 0.12065 0.2794)
			(end 0.12065 0.3048)
			(stroke
				(width 0.1)
				(type default)
			)
			(layer "B.Fab")
		)
		(fp_line
			(start -0.120396 0.2794)
			(end 0.12065 0.2794)
			(stroke
				(width 0.1)
				(type default)
			)
			(layer "B.Fab")
		)
		(fp_line
			(start 0.67945 0.3048)
			(end 0.67945 -0.305054)
			(stroke
				(width 0.1)
				(type default)
			)
			(layer "B.Fab")
		)
		(fp_line
			(start 0.12065 0.3048)
			(end 0.67945 0.3048)
			(stroke
				(width 0.1)
				(type default)
			)
			(layer "B.Fab")
		)
		(fp_line
			(start -0.120396 0.3048)
			(end -0.120396 0.2794)
			(stroke
				(width 0.1)
				(type default)
			)
			(layer "B.Fab")
		)
		(fp_line
			(start -0.67945 0.3048)
			(end -0.120396 0.3048)
			(stroke
				(width 0.1)
				(type default)
			)
			(layer "B.Fab")
		)
		(pad "1" smd circle
			(at 0.40005 0 270)
			(size 0 0)
			(layers "B.Cu" "B.Mask" "B.Paste")
			(net "I3C_SPD_DDREFGH_CPU0_LVC1_SCL_7")
		)
		(pad "2" smd circle
			(at -0.40005 0 270)
			(size 0 0)
			(layers "B.Cu" "B.Mask" "B.Paste")
			(net "I3C_SPD_DDREFGH_CPU0_LVC1_SCL")
		)
	)
)
